(kicad_pcb
	(version 20241229)
	(generator "pcbnew")
	(generator_version "9.0")
	(general
		(thickness 1.294)
		(legacy_teardrops no)
	)
	(paper "A3")
	(title_block
		(title "Kintex 410T devboard")
		(date "2024-04-03")
		(rev "1.1.2")
		(comment 9 "footprints 333-337 of 975")
	)
	(layers
		(0 "F.Cu" mixed)
		(4 "In1.Cu" power)
		(6 "In2.Cu" power)
		(8 "In3.Cu" mixed)
		(10 "In4.Cu" power)
		(12 "In5.Cu" mixed)
		(14 "In6.Cu" power)
		(16 "In7.Cu" mixed)
		(18 "In8.Cu" power)
		(2 "B.Cu" mixed)
		(9 "F.Adhes" user "F.Adhesive")
		(11 "B.Adhes" user "B.Adhesive")
		(13 "F.Paste" user)
		(15 "B.Paste" user)
		(5 "F.SilkS" user "F.Silkscreen")
		(7 "B.SilkS" user "B.Silkscreen")
		(1 "F.Mask" user)
		(3 "B.Mask" user)
		(17 "Dwgs.User" user "User.Drawings")
		(19 "Cmts.User" user "User.Comments")
		(21 "Eco1.User" user "User.Eco1")
		(23 "Eco2.User" user "User.Eco2")
		(25 "Edge.Cuts" user)
		(27 "Margin" user)
		(31 "F.CrtYd" user "F.Courtyard")
		(29 "B.CrtYd" user "B.Courtyard")
		(35 "F.Fab" user)
		(33 "B.Fab" user)
	)
	(footprint "antmicro-footprints:LED_0603_1608Metric_G"
		(layer "F.Cu")
		(at 261.5 91)
		(descr "LED SMD 0603 Green")
		(tags "LED SMD 0603 Green")
		(property "Reference" "D21"
			(at -1.05 1.55 0)
			(layer "F.SilkS")
			(effects
				(font
					(size 0.7 0.7)
					(thickness 0.15)
				)
				(justify left bottom)
			)
		)
		(property "Value" "LED_G_0603_KP-1608CGCK"
			(at 0 1.6 0)
			(layer "F.Fab")
			(effects
				(font
					(size 0.7 0.7)
					(thickness 0.15)
				)
				(justify left bottom)
			)
		)
		(property "Description" "LED, Green, SMD, 0603, 20 mA, 2.1 V, 570 nm"
			(at 0 0 0)
			(layer "F.Fab")
			(hide yes)
			(effects
				(font
					(size 1.27 1.27)
					(thickness 0.15)
				)
			)
		)
		(property "Author" "Antmicro"
			(at 0 0 0)
			(layer "F.Fab")
			(hide yes)
			(effects
				(font
					(size 1 1)
					(thickness 0.15)
				)
			)
		)
		(property "Color" "Green"
			(at 0 0 0)
			(layer "F.Fab")
			(hide yes)
			(effects
				(font
					(size 1 1)
					(thickness 0.15)
				)
			)
		)
		(property "License" "Apache-2.0"
			(at 0 0 0)
			(layer "F.Fab")
			(hide yes)
			(effects
				(font
					(size 1 1)
					(thickness 0.15)
				)
			)
		)
		(property "MPN" "KP-1608CGCK"
			(at 0 0 0)
			(layer "F.Fab")
			(hide yes)
			(effects
				(font
					(size 1 1)
					(thickness 0.15)
				)
			)
		)
		(property "Manufacturer" "Kingbright"
			(at 0 0 0)
			(layer "F.Fab")
			(hide yes)
			(effects
				(font
					(size 1 1)
					(thickness 0.15)
				)
			)
		)
		(sheetname "User GPIO + LED + button + DIP switch")
		(sheetfile "user-gpio.kicad_sch")
		(attr smd)
		(fp_line
			(start -1.18 -0.319)
			(end -1.18 0.321)
			(stroke
				(width 0.15)
				(type solid)
			)
			(layer "F.SilkS")
		)
		(fp_line
			(start -0.094672 0.001008)
			(end -0.24 0.001008)
			(stroke
				(width 0.1)
				(type solid)
			)
			(layer "F.SilkS")
		)
		(fp_line
			(start -0.094672 0.001008)
			(end 0.105328 -0.198992)
			(stroke
				(width 0.1)
				(type solid)
			)
			(layer "F.SilkS")
		)
		(fp_line
			(start -0.094672 0.201008)
			(end -0.094672 -0.198992)
			(stroke
				(width 0.1)
				(type solid)
			)
			(layer "F.SilkS")
		)
		(fp_line
			(start 0.105328 0.001008)
			(end 0.24 0.001)
			(stroke
				(width 0.1)
				(type solid)
			)
			(layer "F.SilkS")
		)
		(fp_line
			(start 0.105328 0.201008)
			(end -0.094672 0.001008)
			(stroke
				(width 0.1)
				(type solid)
			)
			(layer "F.SilkS")
		)
		(fp_line
			(start 0.105328 0.201008)
			(end 0.105328 -0.198992)
			(stroke
				(width 0.1)
				(type solid)
			)
			(layer "F.SilkS")
		)
		(fp_line
			(start 0.22 -0.35)
			(end -0.22 -0.35)
			(stroke
				(width 0.15)
				(type solid)
			)
			(layer "F.SilkS")
		)
		(fp_line
			(start 0.22 0.35)
			(end -0.22 0.35)
			(stroke
				(width 0.15)
				(type solid)
			)
			(layer "F.SilkS")
		)
		(fp_rect
			(start 1.25 0.65)
			(end -1.25 -0.65)
			(stroke
				(width 0.05)
				(type solid)
			)
			(fill no)
			(layer "F.CrtYd")
		)
		(fp_line
			(start -0.199 -0.202)
			(end -0.199 0.1)
			(stroke
				(width 0.15)
				(type solid)
			)
			(layer "F.Fab")
		)
		(fp_line
			(start -0.199 0)
			(end -0.597 0)
			(stroke
				(width 0.15)
				(type solid)
			)
			(layer "F.Fab")
		)
		(fp_line
			(start -0.199 0.2)
			(end -0.199 0.1)
			(stroke
				(width 0.15)
				(type solid)
			)
			(layer "F.Fab")
		)
		(fp_line
			(start -0.101 0)
			(end 0.201 0.2)
			(stroke
				(width 0.15)
				(type solid)
			)
			(layer "F.Fab")
		)
		(fp_line
			(start 0.201 -0.202)
			(end -0.101 0)
			(stroke
				(width 0.15)
				(type solid)
			)
			(layer "F.Fab")
		)
		(fp_line
			(start 0.201 0)
			(end 0.201 -0.202)
			(stroke
				(width 0.15)
				(type solid)
			)
			(layer "F.Fab")
		)
		(fp_line
			(start 0.201 0.2)
			(end 0.201 0)
			(stroke
				(width 0.15)
				(type solid)
			)
			(layer "F.Fab")
		)
		(fp_line
			(start 0.599 0)
			(end 0.201 0)
			(stroke
				(width 0.15)
				(type solid)
			)
			(layer "F.Fab")
		)
		(fp_rect
			(start 0.848 0.4)
			(end -0.85 -0.402)
			(stroke
				(width 0.15)
				(type solid)
			)
			(fill no)
			(layer "F.Fab")
		)
		(pad "1" smd roundrect
			(at -0.7 0 180)
			(size 0.8 1)
			(layers "F.Cu" "F.Mask" "F.Paste")
			(roundrect_rratio 0.2)
			(net 23 "Net-(D21-C)")
			(pinfunction "C")
			(pintype "passive")
		)
		(pad "2" smd roundrect
			(at 0.7 0 180)
			(size 0.8 1)
			(layers "F.Cu" "F.Mask" "F.Paste")
			(roundrect_rratio 0.2)
			(net 781 "Net-(D21-A)")
			(pinfunction "A")
			(pintype "passive")
		)
	)
	(footprint "antmicro-footprints:C_0402_1005Metric"
		(layer "F.Cu")
		(at 243.6 141.6 90)
		(descr "Capacitor SMD 0402")
		(tags "capacitor SMD 0402")
		(property "Reference" "C234"
			(at -1.7 6.5 90)
			(layer "F.SilkS")
			(effects
				(font
					(size 0.7 0.7)
					(thickness 0.15)
				)
				(justify left bottom)
			)
		)
		(property "Value" "C_10u_0402"
			(at 0 1.4 90)
			(layer "F.Fab")
			(effects
				(font
					(size 0.7 0.7)
					(thickness 0.15)
				)
				(justify left bottom)
			)
		)
		(property "Description" "SMD Multilayer Ceramic Capacitor, 10 µF, 6.3 V, 0402 [1005 Metric], ± 20%, X5R, CC Series"
			(at 0 0 90)
			(layer "F.Fab")
			(hide yes)
			(effects
				(font
					(size 1.27 1.27)
					(thickness 0.15)
				)
			)
		)
		(property "Author" "Antmicro"
			(at 385.2 -102 0)
			(layer "F.Fab")
			(hide yes)
			(effects
				(font
					(size 1 1)
					(thickness 0.15)
				)
			)
		)
		(property "Dielectric" ""
			(at 385.2 -102 0)
			(layer "F.Fab")
			(hide yes)
			(effects
				(font
					(size 1 1)
					(thickness 0.15)
				)
			)
		)
		(property "License" "Apache-2.0"
			(at 385.2 -102 0)
			(layer "F.Fab")
			(hide yes)
			(effects
				(font
					(size 1 1)
					(thickness 0.15)
				)
			)
		)
		(property "MPN" "CC0402MRX5R5BB106"
			(at 385.2 -102 0)
			(layer "F.Fab")
			(hide yes)
			(effects
				(font
					(size 1 1)
					(thickness 0.15)
				)
			)
		)
		(property "Manufacturer" "YAGEO"
			(at 385.2 -102 0)
			(layer "F.Fab")
			(hide yes)
			(effects
				(font
					(size 1 1)
					(thickness 0.15)
				)
			)
		)
		(property "Val" "10u"
			(at 385.2 -102 0)
			(layer "F.Fab")
			(hide yes)
			(effects
				(font
					(size 1 1)
					(thickness 0.15)
				)
			)
		)
		(property "Voltage" ""
			(at 385.2 -102 0)
			(layer "F.Fab")
			(hide yes)
			(effects
				(font
					(size 1 1)
					(thickness 0.15)
				)
			)
		)
		(sheetname "USB PHY")
		(sheetfile "usb-phy.kicad_sch")
		(attr smd)
		(fp_rect
			(start -0.925 -0.47)
			(end 0.925 0.47)
			(stroke
				(width 0.05)
				(type default)
			)
			(fill no)
			(layer "F.CrtYd")
		)
		(fp_line
			(start 0.504 -0.25)
			(end 0.504 0.248)
			(stroke
				(width 0.15)
				(type solid)
			)
			(layer "F.Fab")
		)
		(fp_line
			(start -0.494 -0.25)
			(end 0.504 -0.25)
			(stroke
				(width 0.15)
				(type solid)
			)
			(layer "F.Fab")
		)
		(fp_line
			(start 0.504 0.248)
			(end -0.494 0.248)
			(stroke
				(width 0.15)
				(type solid)
			)
			(layer "F.Fab")
		)
		(fp_line
			(start -0.494 0.248)
			(end -0.494 -0.25)
			(stroke
				(width 0.15)
				(type solid)
			)
			(layer "F.Fab")
		)
		(pad "1" smd roundrect
			(at -0.48 0 90)
			(size 0.59 0.64)
			(layers "F.Cu" "F.Mask" "F.Paste")
			(roundrect_rratio 0.25)
			(net 1 "GND")
			(pintype "passive")
		)
		(pad "2" smd roundrect
			(at 0.48 0 90)
			(size 0.59 0.64)
			(layers "F.Cu" "F.Mask" "F.Paste")
			(roundrect_rratio 0.25)
			(net 712 "/USB PHY/FTDI_VCORE")
			(pintype "passive")
		)
	)
	(footprint "antmicro-footprints:R_0402_1005Metric"
		(layer "F.Cu")
		(at 213.9 165.4 90)
		(descr "Resistor SMD 0402")
		(tags "resistor SMD 0402")
		(property "Reference" "R67"
			(at -0.4 -5.25 90)
			(layer "F.SilkS")
			(effects
				(font
					(size 0.7 0.7)
					(thickness 0.15)
				)
				(justify left bottom)
			)
		)
		(property "Value" "R_10k_0402"
			(at 0 1.4 90)
			(layer "F.Fab")
			(effects
				(font
					(size 0.7 0.7)
					(thickness 0.15)
				)
				(justify left bottom)
			)
		)
		(property "Description" "SMD Chip Resistor, 10 kohm, ± 1%, 62.5 mW, 0402 [1005 Metric], Thick Film, General Purpose"
			(at 0 0 90)
			(layer "F.Fab")
			(hide yes)
			(effects
				(font
					(size 1.27 1.27)
					(thickness 0.15)
				)
			)
		)
		(property "Author" "Antmicro"
			(at 379.3 -48.5 0)
			(layer "F.Fab")
			(hide yes)
			(effects
				(font
					(size 1 1)
					(thickness 0.15)
				)
			)
		)
		(property "License" "Apache-2.0"
			(at 379.3 -48.5 0)
			(layer "F.Fab")
			(hide yes)
			(effects
				(font
					(size 1 1)
					(thickness 0.15)
				)
			)
		)
		(property "MPN" "CR0402-FX-1002GLF"
			(at 379.3 -48.5 0)
			(layer "F.Fab")
			(hide yes)
			(effects
				(font
					(size 1 1)
					(thickness 0.15)
				)
			)
		)
		(property "Manufacturer" "Bourns"
			(at 379.3 -48.5 0)
			(layer "F.Fab")
			(hide yes)
			(effects
				(font
					(size 1 1)
					(thickness 0.15)
				)
			)
		)
		(property "Tolerance" "1%"
			(at 379.3 -48.5 0)
			(layer "F.Fab")
			(hide yes)
			(effects
				(font
					(size 1 1)
					(thickness 0.15)
				)
			)
		)
		(property "Val" "10k"
			(at 379.3 -48.5 0)
			(layer "F.Fab")
			(hide yes)
			(effects
				(font
					(size 1 1)
					(thickness 0.15)
				)
			)
		)
		(sheetname "SPI Flash + SD Card")
		(sheetfile "spi-flash.kicad_sch")
		(attr smd)
		(fp_rect
			(start -0.925 -0.47)
			(end 0.925 0.47)
			(stroke
				(width 0.05)
				(type default)
			)
			(fill no)
			(layer "F.CrtYd")
		)
		(fp_rect
			(start -0.5 -0.25)
			(end 0.5 0.25)
			(stroke
				(width 0.15)
				(type solid)
			)
			(fill no)
			(layer "F.Fab")
		)
		(pad "1" smd roundrect
			(at -0.48 0 90)
			(size 0.59 0.64)
			(layers "F.Cu" "F.Mask" "F.Paste")
			(roundrect_rratio 0.25)
			(net 404 "/FPGA Bank 33 & 34/USR_FLASH_0.DQ2")
			(pintype "passive")
		)
		(pad "2" smd roundrect
			(at 0.48 0 90)
			(size 0.59 0.64)
			(layers "F.Cu" "F.Mask" "F.Paste")
			(roundrect_rratio 0.25)
			(net 26 "+1V8")
			(pintype "passive")
		)
	)
	(footprint "antmicro-footprints:FB_0603_1608Metric"
		(layer "F.Cu")
		(at 256.845 136.535 180)
		(property "Reference" "FB5"
			(at 0.795 4.535 180)
			(layer "F.SilkS")
			(effects
				(font
					(size 0.7 0.7)
					(thickness 0.15)
				)
				(justify left bottom)
			)
		)
		(property "Value" "FB_600Z_0.5A_Murata-BLM18AG_0603"
			(at 0 1.7 180)
			(layer "F.Fab")
			(effects
				(font
					(size 0.7 0.7)
					(thickness 0.15)
				)
				(justify left bottom)
			)
		)
		(property "Description" "Ferrite Bead, 0603 [1608 Metric], 600 ohm, 500 mA, BLM18A, 0.38 ohm, ± 25%, General use"
			(at 0 0 180)
			(layer "F.Fab")
			(hide yes)
			(effects
				(font
					(size 1.27 1.27)
					(thickness 0.15)
				)
			)
		)
		(property "Author" "Antmicro"
			(at 513.69 273.07 0)
			(layer "F.Fab")
			(hide yes)
			(effects
				(font
					(size 1 1)
					(thickness 0.15)
				)
			)
		)
		(property "Current" ""
			(at 513.69 273.07 0)
			(layer "F.Fab")
			(hide yes)
			(effects
				(font
					(size 1 1)
					(thickness 0.15)
				)
			)
		)
		(property "License" "Apache-2.0"
			(at 513.69 273.07 0)
			(layer "F.Fab")
			(hide yes)
			(effects
				(font
					(size 1 1)
					(thickness 0.15)
				)
			)
		)
		(property "MPN" "BLM18AG601SN1D"
			(at 513.69 273.07 0)
			(layer "F.Fab")
			(hide yes)
			(effects
				(font
					(size 1 1)
					(thickness 0.15)
				)
			)
		)
		(property "Manufacturer" "Murata"
			(at 513.69 273.07 0)
			(layer "F.Fab")
			(hide yes)
			(effects
				(font
					(size 1 1)
					(thickness 0.15)
				)
			)
		)
		(property "Val" "600Z/0.5A"
			(at 513.69 273.07 0)
			(layer "F.Fab")
			(hide yes)
			(effects
				(font
					(size 1 1)
					(thickness 0.15)
				)
			)
		)
		(sheetname "USB PHY")
		(sheetfile "usb-phy.kicad_sch")
		(attr smd)
		(fp_line
			(start -0.15 0.4)
			(end 0.15 0.4)
			(stroke
				(width 0.15)
				(type solid)
			)
			(layer "F.SilkS")
		)
		(fp_line
			(start -0.15 -0.4)
			(end 0.15 -0.4)
			(stroke
				(width 0.15)
				(type solid)
			)
			(layer "F.SilkS")
		)
		(fp_rect
			(start -1.25 -0.65)
			(end 1.25 0.65)
			(stroke
				(width 0.05)
				(type solid)
			)
			(fill no)
			(layer "F.CrtYd")
		)
		(fp_line
			(start 0.8 0.406)
			(end -0.803 0.406)
			(stroke
				(width 0.15)
				(type solid)
			)
			(layer "F.Fab")
		)
		(fp_line
			(start 0.8 -0.408)
			(end 0.8 0.406)
			(stroke
				(width 0.15)
				(type solid)
			)
			(layer "F.Fab")
		)
		(fp_line
			(start 0.8 -0.408)
			(end -0.803 -0.408)
			(stroke
				(width 0.15)
				(type solid)
			)
			(layer "F.Fab")
		)
		(fp_line
			(start -0.803 0.406)
			(end -0.803 -0.408)
			(stroke
				(width 0.15)
				(type solid)
			)
			(layer "F.Fab")
		)
		(pad "1" smd roundrect
			(at -0.7 0 180)
			(size 0.8 1)
			(layers "F.Cu" "F.Mask" "F.Paste")
			(roundrect_rratio 0.2)
			(net 707 "/USB PHY/FTDI_3V3")
			(pintype "passive")
		)
		(pad "2" smd roundrect
			(at 0.7 0 180)
			(size 0.8 1)
			(layers "F.Cu" "F.Mask" "F.Paste")
			(roundrect_rratio 0.2)
			(net 714 "/USB PHY/FTDI_VPHY")
			(pintype "passive")
		)
	)
	(footprint "antmicro-footprints:ULS-12_5-D48N-C"
		(layer "F.Cu")
		(at 228 185.428 180)
		(property "Reference" "U8"
			(at -3.5 17.428 270)
			(layer "F.SilkS")
			(effects
				(font
					(size 0.7 0.7)
					(thickness 0.15)
				)
				(justify left bottom)
			)
		)
		(property "Value" "ULS-12_8.3-D48N-C"
			(at 0 20 180)
			(layer "F.Fab")
			(effects
				(font
					(size 0.7 0.7)
					(thickness 0.15)
				)
				(justify left bottom)
			)
		)
		(property "Description" "DC/DC converter"
			(at 0 0 180)
			(layer "F.Fab")
			(hide yes)
			(effects
				(font
					(size 1.27 1.27)
					(thickness 0.15)
				)
			)
		)
		(property "Author" "Antmicro"
			(at 456 370.856 0)
			(layer "F.Fab")
			(hide yes)
			(effects
				(font
					(size 1 1)
					(thickness 0.15)
				)
			)
		)
		(property "License" "Apache-2.0"
			(at 456 370.856 0)
			(layer "F.Fab")
			(hide yes)
			(effects
				(font
					(size 1 1)
					(thickness 0.15)
				)
			)
		)
		(property "MPN" "ULS-12/8.3-D48N-C"
			(at 456 370.856 0)
			(layer "F.Fab")
			(hide yes)
			(effects
				(font
					(size 1 1)
					(thickness 0.15)
				)
			)
		)
		(property "Manufacturer" "Murata"
			(at 456 370.856 0)
			(layer "F.Fab")
			(hide yes)
			(effects
				(font
					(size 1 1)
					(thickness 0.15)
				)
			)
		)
		(sheetname "Power supply")
		(sheetfile "power-supply.kicad_sch")
		(attr through_hole)
		(fp_line
			(start 30.499 18.818)
			(end -2.5 18.818)
			(stroke
				(width 0.15)
				(type solid)
			)
			(layer "F.SilkS")
		)
		(fp_line
			(start 30.499 -4.08)
			(end 30.499 18.818)
			(stroke
				(width 0.15)
				(type solid)
			)
			(layer "F.SilkS")
		)
		(fp_line
			(start -2.5 18.818)
			(end -2.5 -4.08)
			(stroke
				(width 0.15)
				(type solid)
			)
			(layer "F.SilkS")
		)
		(fp_line
			(start -2.5 -4.08)
			(end 30.499 -4.08)
			(stroke
				(width 0.15)
				(type solid)
			)
			(layer "F.SilkS")
		)
		(fp_circle
			(center -1.9 0)
			(end -1.85 0.05)
			(stroke
				(width 0.15)
				(type solid)
			)
			(fill yes)
			(layer "F.SilkS")
		)
		(fp_rect
			(start -3.507 -4.858)
			(end 31.513 20.002)
			(stroke
				(width 0.05)
				(type solid)
			)
			(fill no)
			(layer "F.CrtYd")
		)
		(fp_line
			(start 30.499 18.818)
			(end -2.5 18.818)
			(stroke
				(width 0.15)
				(type solid)
			)
			(layer "F.Fab")
		)
		(fp_line
			(start 30.499 -4.08)
			(end 30.499 18.818)
			(stroke
				(width 0.15)
				(type solid)
			)
			(layer "F.Fab")
		)
		(fp_line
			(start -0.1 -4.05)
			(end 30.499 -4.08)
			(stroke
				(width 0.15)
				(type solid)
			)
			(layer "F.Fab")
		)
		(fp_line
			(start -2.5 18.818)
			(end -2.5 -1.65)
			(stroke
				(width 0.15)
				(type solid)
			)
			(layer "F.Fab")
		)
		(fp_line
			(start -2.5 -1.65)
			(end -0.1 -4.05)
			(stroke
				(width 0.15)
				(type solid)
			)
			(layer "F.Fab")
		)
		(pad "1" thru_hole rect
			(at 0 0 180)
			(size 2.54 2.54)
			(drill 1.4)
			(layers "*.Cu" "*.Mask")
			(remove_unused_layers no)
			(net 698 "/Power supply/VDD")
			(pinfunction "VIN+")
			(pintype "power_in")
		)
		(pad "2" thru_hole circle
			(at 0 7.618 180)
			(size 2.54 2.54)
			(drill 1.4)
			(layers "*.Cu" "*.Mask")
			(remove_unused_layers no)
			(net 798 "/Power supply/POE_ACTIVE")
			(pinfunction "CTRL")
			(pintype "input")
		)
		(pad "3" thru_hole circle
			(at 0 15.239 180)
			(size 2.54 2.54)
			(drill 1.4)
			(layers "*.Cu" "*.Mask")
			(remove_unused_layers no)
			(net 699 "GNDD")
			(pinfunction "VIN-")
			(pintype "power_in")
		)
		(pad "4" thru_hole circle
			(at 27.938 15.239 180)
			(size 2.54 2.54)
			(drill 1.956)
			(layers "*.Cu" "*.Mask")
			(remove_unused_layers no)
			(net 1 "GND")
			(pinfunction "VOUT-")
			(pintype "power_out")
		)
		(pad "5" thru_hole circle
			(at 27.938 11.429 180)
			(size 2.54 2.54)
			(drill 1.4)
			(layers "*.Cu" "*.Mask")
			(remove_unused_layers no)
			(net 1 "GND")
			(pinfunction "SENSE-")
			(pintype "passive")
		)
		(pad "6" thru_hole circle
			(at 27.938 7.618 180)
			(size 2.54 2.54)
			(drill 1.4)
			(layers "*.Cu" "*.Mask")
			(remove_unused_layers no)
			(net 365 "Net-(U8-TRIM)")
			(pinfunction "TRIM")
			(pintype "input")
		)
		(pad "7" thru_hole circle
			(at 27.938 3.809 180)
			(size 2.54 2.54)
			(drill 1.4)
			(layers "*.Cu" "*.Mask")
			(remove_unused_layers no)
			(net 956 "/DC-DC Converters/POE_DC")
			(pinfunction "SENSE+")
			(pintype "passive")
		)
		(pad "8" thru_hole circle
			(at 27.938 0 180)
			(size 2.54 2.54)
			(drill 1.956)
			(layers "*.Cu" "*.Mask")
			(remove_unused_layers no)
			(net 956 "/DC-DC Converters/POE_DC")
			(pinfunction "VOUT+")
			(pintype "power_out")
		)
	)
)
